# BASEBOARD_FAB2 (Tioga Pass) — schematic parts with pin connectivity, parts 2404–2441 of 4751; source: Cadence DE-HDL packaged netlist (pstxprt.dat, pstxnet.dat, pstchip.dat)

J9U2  SCONN288_H44441003  SCONN  pkg PIP  page 82
  1  \12v\(1)  = P12V_NVDIMM_GHJ
  2  VSS(93)  GROUND  = GND
  3  DQ(4)  BI  = M_J_DQ<4>
  4  VSS(92)  GROUND  = GND
  5  DQ(0)  BI  = M_J_DQ<0>
  6  VSS(91)  GROUND  = GND
  7  DQS9P  BI  = M_J_DQS_DP<9>
  8  DQS9N  BI  = M_J_DQS_DN<9>
  9  VSS(90)  GROUND  = GND
  10  DQ(6)  BI  = M_J_DQ<6>
  11  VSS(89)  GROUND  = GND
  12  DQ(2)  BI  = M_J_DQ<2>
  13  VSS(88)  GROUND  = GND
  14  DQ(12)  BI  = M_J_DQ<12>
  15  VSS(87)  GROUND  = GND
  16  DQ(8)  BI  = M_J_DQ<8>
  17  VSS(86)  GROUND  = GND
  18  DQS10P  BI  = M_J_DQS_DP<10>
  19  DQS10N  BI  = M_J_DQS_DN<10>
  20  VSS(85)  GROUND  = GND
  21  DQ(14)  BI  = M_J_DQ<14>
  22  VSS(84)  GROUND  = GND
  23  DQ(10)  BI  = M_J_DQ<10>
  24  VSS(83)  GROUND  = GND
  25  DQ(20)  BI  = M_J_DQ<20>
  26  VSS(82)  GROUND  = GND
  27  DQ(16)  BI  = M_J_DQ<16>
  28  VSS(81)  GROUND  = GND
  29  DQS11P  BI  = M_J_DQS_DP<11>
  30  DQS11N  BI  = M_J_DQS_DN<11>
  31  VSS(80)  GROUND  = GND
  32  DQ(22)  BI  = M_J_DQ<22>
  33  VSS(79)  GROUND  = GND
  34  DQ(18)  BI  = M_J_DQ<18>
  35  VSS(78)  GROUND  = GND
  36  DQ(28)  BI  = M_J_DQ<28>
  37  VSS(77)  GROUND  = GND
  38  DQ(24)  BI  = M_J_DQ<24>
  39  VSS(76)  GROUND  = GND
  40  DQS12P  BI  = M_J_DQS_DP<12>
  41  DQS12N  BI  = M_J_DQS_DN<12>
  42  VSS(75)  GROUND  = GND
  43  DQ(30)  BI  = M_J_DQ<30>
  44  VSS(74)  GROUND  = GND
  45  DQ(26)  BI  = M_J_DQ<26>
  46  VSS(73)  GROUND  = GND
  47  CB(4)  BI  = M_J_ECC<4>
  48  VSS(72)  GROUND  = GND
  49  CB(0)  BI  = M_J_ECC<0>
  50  VSS(71)  GROUND  = GND
  51  DQS17P  BI  = M_J_DQS_DP<17>
  52  DQS17N  BI  = M_J_DQS_DN<17>
  53  VSS(70)  GROUND  = GND
  54  CB(6)  BI  = M_J_ECC<6>
  55  VSS(69)  GROUND  = GND
  56  CB(2)  BI  = M_J_ECC<2>
  57  VSS(68)  GROUND  = GND
  58  RESET_N  BI  = M_GHJ_RST_N
  59  VDD(25)  POWER  = PVDDQ_GHJ
  60  CKE(0)  BI  = M_J_CKE<2>
  61  VDD(24)  POWER  = PVDDQ_GHJ
  62  ACT_N  BI  = M_J_ACT_N
  63  BG(0)  BI  = M_J_BG<0>
  64  VDD(23)  POWER  = PVDDQ_GHJ
  65  A12  BI  = M_J_MA<12>
  66  A9  BI  = M_J_MA<9>
  67  VDD(22)  POWER  = PVDDQ_GHJ
  68  A8  BI  = M_J_MA<8>
  69  A6  BI  = M_J_MA<6>
  70  VDD(21)  POWER  = PVDDQ_GHJ
  71  A3  BI  = M_J_MA<3>
  72  A1  BI  = M_J_MA<1>
  73  VDD(20)  POWER  = PVDDQ_GHJ
  74  CK0P  BI  = M_J_CLK_DP<2>
  75  CK0N  BI  = M_J_CLK_DN<2>
  76  VDD(19)  POWER  = PVDDQ_GHJ
  77  VTT(1)  POWER  = PVTT_GHJ
  78  EVENT_N  BI  = FM_DIMM_EVENT_COD_N
  79  A0  BI  = M_J_MA<0>
  80  VDD(18)  POWER  = PVDDQ_GHJ
  81  BA(0)  BI  = M_J_BA<0>
  82  A16_RAS_N  BI  = M_J_MA<16>
  83  VDD(17)  POWER  = PVDDQ_GHJ
  84  S0_N  BI  = M_J_CS_N<4>
  85  VDD(16)  POWER  = PVDDQ_GHJ
  86  A15_CAS_N  BI  = M_J_MA<15>
  87  ODT(0)  BI  = M_J_ODT<2>
  88  VDD(15)  POWER  = PVDDQ_GHJ
  89  S1_N  BI  = M_J_CS_N<5>
  90  VDD(14)  POWER  = PVDDQ_GHJ
  91  ODT(1)  BI  = M_J_ODT<3>
  92  VDD(13)  POWER  = PVDDQ_GHJ
  93  S2_N_C(0)  BI  = M_J_CS_N<6>
  94  VSS(67)  GROUND  = GND
  95  DQ(36)  BI  = M_J_DQ<36>
  96  VSS(66)  GROUND  = GND
  97  DQ(32)  BI  = M_J_DQ<32>
  98  VSS(65)  GROUND  = GND
  99  DQS13P  BI  = M_J_DQS_DP<13>
  100  DQS13N  BI  = M_J_DQS_DN<13>
  101  VSS(64)  GROUND  = GND
  102  DQ(38)  BI  = M_J_DQ<38>
  103  VSS(63)  GROUND  = GND
  104  DQ(34)  BI  = M_J_DQ<34>
  105  VSS(62)  GROUND  = GND
  106  DQ(44)  BI  = M_J_DQ<44>
  107  VSS(61)  GROUND  = GND
  108  DQ(40)  BI  = M_J_DQ<40>
  109  VSS(60)  GROUND  = GND
  110  DQS14P  BI  = M_J_DQS_DP<14>
  111  DQS14N  BI  = M_J_DQS_DN<14>
  112  VSS(59)  GROUND  = GND
  113  DQ(46)  BI  = M_J_DQ<46>
  114  VSS(58)  GROUND  = GND
  115  DQ(42)  BI  = M_J_DQ<42>
  116  VSS(57)  GROUND  = GND
  117  DQ(52)  BI  = M_J_DQ<52>
  118  VSS(56)  GROUND  = GND
  119  DQ(48)  BI  = M_J_DQ<48>
  120  VSS(55)  GROUND  = GND
  121  DQS15P  BI  = M_J_DQS_DP<15>
  122  DQS15N  BI  = M_J_DQS_DN<15>
  123  VSS(54)  GROUND  = GND
  124  DQ(54)  BI  = M_J_DQ<54>
  125  VSS(53)  GROUND  = GND
  126  DQ(50)  BI  = M_J_DQ<50>
  127  VSS(52)  GROUND  = GND
  128  DQ(60)  BI  = M_J_DQ<60>
  129  VSS(51)  GROUND  = GND
  130  DQ(56)  BI  = M_J_DQ<56>
  131  VSS(50)  GROUND  = GND
  132  DQS16P  BI  = M_J_DQS_DP<16>
  133  DQS16N  BI  = M_J_DQS_DN<16>
  134  VSS(49)  GROUND  = GND
  135  DQ(62)  BI  = M_J_DQ<62>
  136  VSS(48)  GROUND  = GND
  137  DQ(58)  BI  = M_J_DQ<58>
  138  VSS(47)  GROUND  = GND
  139  SA(0)  BI  = PVPP_GHJ
  140  SA(1)  BI  = GND
  141  SCL  BI  = SMB_DDR_GHJ_VPP_SCL
  142  VPP(4)  POWER  = PVPP_GHJ
  143  VPP(3)  POWER  = PVPP_GHJ
  144  RFU(2)  BI  = TP_CH_J_DIMM_J1_RFU_2
  145  \12v\(0)  = P12V_NVDIMM_GHJ
  146  VREFCA  BI  = M_J_VREF
  147  VSS(46)  GROUND  = GND
  148  DQ(5)  BI  = M_J_DQ<5>
  149  VSS(45)  GROUND  = GND
  150  DQ(1)  BI  = M_J_DQ<1>
  151  VSS(44)  GROUND  = GND
  152  DQS0N  BI  = M_J_DQS_DN<0>
  153  DQS0P  BI  = M_J_DQS_DP<0>
  154  VSS(43)  GROUND  = GND
  155  DQ(7)  BI  = M_J_DQ<7>
  156  VSS(42)  GROUND  = GND
  157  DQ(3)  BI  = M_J_DQ<3>
  158  VSS(41)  GROUND  = GND
  159  DQ(13)  BI  = M_J_DQ<13>
  160  VSS(40)  GROUND  = GND
  161  DQ(9)  BI  = M_J_DQ<9>
  162  VSS(39)  GROUND  = GND
  163  DQS1N  BI  = M_J_DQS_DN<1>
  164  DQS1P  BI  = M_J_DQS_DP<1>
  165  VSS(38)  GROUND  = GND
  166  DQ(15)  BI  = M_J_DQ<15>
  167  VSS(37)  GROUND  = GND
  168  DQ(11)  BI  = M_J_DQ<11>
  169  VSS(36)  GROUND  = GND
  170  DQ(21)  BI  = M_J_DQ<21>
  171  VSS(35)  GROUND  = GND
  172  DQ(17)  BI  = M_J_DQ<17>
  173  VSS(34)  GROUND  = GND
  174  DQS2N  BI  = M_J_DQS_DN<2>
  175  DQS2P  BI  = M_J_DQS_DP<2>
  176  VSS(33)  GROUND  = GND
  177  DQ(23)  BI  = M_J_DQ<23>
  178  VSS(32)  GROUND  = GND
  179  DQ(19)  BI  = M_J_DQ<19>
  180  VSS(31)  GROUND  = GND
  181  DQ(29)  BI  = M_J_DQ<29>
  182  VSS(30)  GROUND  = GND
  183  DQ(25)  BI  = M_J_DQ<25>
  184  VSS(29)  GROUND  = GND
  185  DQS3N  BI  = M_J_DQS_DN<3>
  186  DQS3P  BI  = M_J_DQS_DP<3>
  187  VSS(28)  GROUND  = GND
  188  DQ(31)  BI  = M_J_DQ<31>
  189  VSS(27)  GROUND  = GND
  190  DQ(27)  BI  = M_J_DQ<27>
  191  VSS(26)  GROUND  = GND
  192  CB(5)  BI  = M_J_ECC<5>
  193  VSS(25)  GROUND  = GND
  194  CB(1)  BI  = M_J_ECC<1>
  195  VSS(24)  GROUND  = GND
  196  DQS8N  BI  = M_J_DQS_DN<8>
  197  DQS8P  BI  = M_J_DQS_DP<8>
  198  VSS(23)  GROUND  = GND
  199  CB(7)  BI  = M_J_ECC<7>
  200  VSS(22)  GROUND  = GND
  201  CB(3)  BI  = M_J_ECC<3>
  202  VSS(21)  GROUND  = GND
  203  CKE(1)  BI  = M_J_CKE<3>
  204  VDD(12)  POWER  = PVDDQ_GHJ
  205  RFU(0)  BI  = TP_CH_J_DIMM_J1_RFU_0
  206  VDD(11)  POWER  = PVDDQ_GHJ
  207  BG(1)  BI  = M_J_BG<1>
  208  ALERT_N  BI  = M_J_ALERT_N
  209  VDD(10)  POWER  = PVDDQ_GHJ
  210  A11  BI  = M_J_MA<11>
  211  A7  BI  = M_J_MA<7>
  212  VDD(9)  POWER  = PVDDQ_GHJ
  213  A5  BI  = M_J_MA<5>
  214  A4  BI  = M_J_MA<4>
  215  VDD(8)  POWER  = PVDDQ_GHJ
  216  A2  BI  = M_J_MA<2>
  217  VDD(7)  POWER  = PVDDQ_GHJ
  218  CK1P  BI  = M_J_CLK_DP<3>
  219  CK1N  BI  = M_J_CLK_DN<3>
  220  VDD(6)  POWER  = PVDDQ_GHJ
  221  VTT(0)  POWER  = PVTT_GHJ
  222  PAR  BI  = M_J_PAR
  223  VDD(5)  POWER  = PVDDQ_GHJ
  224  BA(1)  BI  = M_J_BA<1>
  225  A10  BI  = M_J_MA<10>
  226  VDD(4)  POWER  = PVDDQ_GHJ
  227  RFU(1)  BI  = TP_CH_J_DIMM_J1_RFU_1
  228  A14_WE_N  BI  = M_J_MA<14>
  229  VDD(3)  POWER  = PVDDQ_GHJ
  230  SAVE_N_NC  BI  = FM_ADR_COMPLETE_GHJ_N
  231  VDD(2)  POWER  = PVDDQ_GHJ
  232  A13  BI  = M_J_MA<13>
  233  VDD(1)  POWER  = PVDDQ_GHJ
  234  A17  BI  = M_J_MA<17>
  235  C(2)  BI  = M_J_C<2>
  236  VDD(0)  POWER  = PVDDQ_GHJ
  237  S3_N_C(1)  BI  = M_J_CS_N<7>
  238  SA(2)  BI  = PVPP_GHJ
  239  VSS(20)  GROUND  = GND
  240  DQ(37)  BI  = M_J_DQ<37>
  241  VSS(19)  GROUND  = GND
  242  DQ(33)  BI  = M_J_DQ<33>
  243  VSS(18)  GROUND  = GND
  244  DQS4N  BI  = M_J_DQS_DN<4>
  245  DQS4P  BI  = M_J_DQS_DP<4>
  246  VSS(17)  GROUND  = GND
  247  DQ(39)  BI  = M_J_DQ<39>
  248  VSS(16)  GROUND  = GND
  249  DQ(35)  BI  = M_J_DQ<35>
  250  VSS(15)  GROUND  = GND
  251  DQ(45)  BI  = M_J_DQ<45>
  252  VSS(14)  GROUND  = GND
  253  DQ(41)  BI  = M_J_DQ<41>
  254  VSS(13)  GROUND  = GND
  255  DQS5N  BI  = M_J_DQS_DN<5>
  256  DQS5P  BI  = M_J_DQS_DP<5>
  257  VSS(12)  GROUND  = GND
  258  DQ(47)  BI  = M_J_DQ<47>
  259  VSS(11)  GROUND  = GND
  260  DQ(43)  BI  = M_J_DQ<43>
  261  VSS(10)  GROUND  = GND
  262  DQ(53)  BI  = M_J_DQ<53>
  263  VSS(9)  GROUND  = GND
  264  DQ(49)  BI  = M_J_DQ<49>
  265  VSS(8)  GROUND  = GND
  266  DQS6N  BI  = M_J_DQS_DN<6>
  267  DQS6P  BI  = M_J_DQS_DP<6>
  268  VSS(7)  GROUND  = GND
  269  DQ(55)  BI  = M_J_DQ<55>
  270  VSS(6)  GROUND  = GND
  271  DQ(51)  BI  = M_J_DQ<51>
  272  VSS(5)  GROUND  = GND
  273  DQ(61)  BI  = M_J_DQ<61>
  274  VSS(4)  GROUND  = GND
  275  DQ(57)  BI  = M_J_DQ<57>
  276  VSS(3)  GROUND  = GND
  277  DQS7N  BI  = M_J_DQS_DN<7>
  278  DQS7P  BI  = M_J_DQS_DP<7>
  279  VSS(2)  GROUND  = GND
  280  DQ(63)  BI  = M_J_DQ<63>
  281  VSS(1)  GROUND  = GND
  282  DQ(59)  BI  = M_J_DQ<59>
  283  VSS(0)  GROUND  = GND
  284  VDDSPD  BI  = PVPP_GHJ
  285  SDA  BI  = SMB_DDR_GHJ_VPP_SDA
  286  VPP(1)  POWER  = PVPP_GHJ
  287  VPP(0)  POWER  = PVPP_GHJ
  288  VPP(2)  POWER  = PVPP_GHJ

J10W1  LOTES-CON4-S1-GP  pkg CONN-G7  page 161
  1  \1\  UNSPEC  = GND
  2  \2\  UNSPEC  = P12V_FAN
  3  \3\  UNSPEC  = FAN_TACH2_CPU1_D1
  4  \4\  UNSPEC  = FAN_PWM_OUT_SYS1_R
  NP1  NP1  UNSPEC  = NC

J25W1  SMC-CON13-GP  pkg CONN-GC2  page 252
  1  \1\  UNSPEC  = V_IO_R_J
  2  \2\  UNSPEC  = GND
  3  \3\  UNSPEC  = V_IO_G_J
  4  \4\  UNSPEC  = GND
  5  \5\  UNSPEC  = V_IO_B_J
  6  \6\  UNSPEC  = GND
  7  \7\  UNSPEC  = V_IO_VSYNC_J
  8  \8\  UNSPEC  = GND
  9  \9\  UNSPEC  = V_IO_HSYNC_J
  10  \10\  UNSPEC  = GND
  11  \11\  UNSPEC  = V_IBMC_5V_DDC_SDA_J
  12  \12\  UNSPEC  = V_IBMC_5V_DDC_SCL_J
  13  \13\  UNSPEC  = P5V_VGA
  PTH1  PTH1  UNSPEC  = GND
  PTH2  PTH2  UNSPEC  = GND

J30W1  SKT-USB32-8-GP  pkg SOCKET-G4  page 253
  A1  GND(0)  POWER  = GND
  A2  SSTXP1  UNSPEC  = USB3_P01_FB_TXP
  A3  SSTXN1  UNSPEC  = USB3_P01_FB_TXN
  A4  VBUS(0)  POWER  = P5V_STBY_USBC
  A5  CC1  UNSPEC  = NC
  A6  DP1  UNSPEC  = NC
  A7  DN1  UNSPEC  = NC
  A8  SBU1  UNSPEC  = NC
  A9  VBUS(1)  POWER  = P5V_STBY_USBC
  A10  SSRXN2  UNSPEC  = NC
  A11  SSRXP2  UNSPEC  = NC
  A12  GND(1)  POWER  = GND
  B1  GND(2)  POWER  = GND
  B2  SSTXP2  UNSPEC  = NC
  B3  SSTXN2  UNSPEC  = NC
  B4  VBUS(2)  POWER  = P5V_STBY_USBC
  B5  CC2  UNSPEC  = NC
  B6  DP2  UNSPEC  = NC
  B7  DN2  UNSPEC  = NC
  B8  SBU2  UNSPEC  = NC
  B9  VBUS(3)  POWER  = P5V_STBY_USBC
  B10  SSRXN1  UNSPEC  = USB3_P01_FB_RXN
  B11  SSRXP1  UNSPEC  = USB3_P01_FB_RXP
  B12  GND(3)  POWER  = GND
  NP1  NP1  UNSPEC  = NC
  NP2  NP2  UNSPEC  = NC
  PTH1  PTH1  UNSPEC  = GND
  PTH2  PTH2  UNSPEC  = GND
  PTH3  PTH3  UNSPEC  = GND
  PTH4  PTH4  UNSPEC  = GND
  PTH5  PTH5  UNSPEC  = GND
  PTH6  PTH6  UNSPEC  = GND
  PTH7  PTH7  UNSPEC  = GND
  PTH8  PTH8  UNSPEC  = GND

JA9G1  SKT-RJ45-LED-XFOR-1-GP  pkg SOCKET-G2  page 141
  1  \1\  UNSPEC  = GND
  2  \2\  UNSPEC  = GND
  L1  L1  UNSPEC  = LED_LAN_2_R_N
  L2  L2  UNSPEC  = LED_LAN_0_R_N
  L3  L3  UNSPEC  = LED_LAN_1_R_N
  L4  L4  UNSPEC  = NIC_LED_ACT_ANODE_R
  R1  R1  UNSPEC  = GND_LAN_TRCT1234_C
  R2  R2  UNSPEC  = NIC_MDI_SPRV_RJ45_0_R_DP
  R3  R3  UNSPEC  = NIC_MDI_SPRV_RJ45_0_R_DN
  R4  R4  UNSPEC  = NIC_MDI_SPRV_RJ45_1_R_DP
  R5  R5  UNSPEC  = NIC_MDI_SPRV_RJ45_1_R_DN
  R6  R6  UNSPEC  = GND
  R7  R7  UNSPEC  = NIC_MDI_SPRV_RJ45_2_R_DP
  R8  R8  UNSPEC  = NIC_MDI_SPRV_RJ45_2_R_DN
  R9  R9  UNSPEC  = NIC_MDI_SPRV_RJ45_3_R_DP
  R10  R10  UNSPEC  = NIC_MDI_SPRV_RJ45_3_R_DN
  R11  R11  UNSPEC  = GND_LAN_TRCT1234_C

L1A1  IND-120NH-30-GP  pkg DISCRET-GB2  page 227 : 1 = VR_PVDDQ_KLM_PH2_SW ; 2 = PVDDQ_KLM
L1A2  IND-120NH-30-GP  pkg DISCRET-GB2  page 227 : 1 = VR_PVDDQ_KLM_PH1_SW ; 2 = PVDDQ_KLM
L1B1  IND-100NH-35-GP  pkg DISCRET-G8  page 228 : 1 = P12V_STBY ; 2 = VR_FET_SW_P12V_STBY_PVDDQ_KLM
L1B2  IND-80NH-1-GP  pkg DISCRET-GC2  page 209 : 1 = P12V_STBY ; 2 = VR_FET_SW_P12V_STBY_PVCCIN_CPU1
L1C1  IND-300NH-20-GP  pkg DISCRET-GB1  page 210 : 1 = VR_PVSA_CPU1_PHASE_SW ; 2 = PVSA_CPU1
L1C2  IND-120NH-30-GP  pkg DISCRET-GB2  page 209 : 1 = VR_PVCCIN_CPU1_PHASE5 ; 2 = PVCCIN_CPU1
L1D1  IND-120NH-30-GP  pkg DISCRET-GB2  page 208 : 1 = VR_PVCCIN_CPU1_PHASE4 ; 2 = PVCCIN_CPU1
L1D2  IND-120NH-30-GP  pkg DISCRET-GB2  page 208 : 1 = VR_PVCCIN_CPU1_PHASE3 ; 2 = PVCCIN_CPU1
L1D3  IND-120NH-30-GP  pkg DISCRET-GB2  page 207 : 1 = VR_PVCCIN_CPU1_PHASE2 ; 2 = PVCCIN_CPU1
L1E1  IND-120NH-30-GP  pkg DISCRET-GB2  page 207 : 1 = VR_PVCCIN_CPU1_PHASE1 ; 2 = PVCCIN_CPU1
L1F1  IND-100NH-35-GP  pkg DISCRET-G8  page 225 : 1 = P12V_STBY ; 2 = VR_FET_SW_P12V_STBY_PVDDQ_GHJ
L1F2  IND-120NH-30-GP  pkg DISCRET-GB2  page 224 : 1 = VR_PVDDQ_GHJ_PH2_SW ; 2 = PVDDQ_GHJ
L1G1  IND-120NH-30-GP  pkg DISCRET-GB2  page 224 : 1 = VR_PVDDQ_GHJ_PH1_SW ; 2 = PVDDQ_GHJ

L1M2  CHOKE_4PIN  90 OHM IND  pkg SMLF  page 176
  1  A1  UNSPEC  = USB2_P01_DN
  2  A2  UNSPEC  = USB2_P01_DP
  3  B1  UNSPEC  = USB2_P01_ESD_DP
  4  B2  UNSPEC  = USB2_P01_ESD_DN

L2M1  INDUCTOR  0.022UH IND  pkg SMT  page 127 : 1 = P1V05_PCH_STBY ; 2 = P1V05_PCH_STBY_KR_PLL
L4A1  INDUCTOR  0.47UH 1% IND  pkg SM  page 234 : 1 = VR_PVPP_KLM_PHASE ; 2 = PVPP_KLM
L4C1  IND-80NH-1-GP  pkg DISCRET-GC2  page 204 : 1 = P12V_STBY ; 2 = VR_FET_SW_P12V_STBY_PVCCIN_CPU0
L4C2  IND-300NH-20-GP  pkg DISCRET-GB1  page 205 : 1 = VR_PVSA_CPU0_PHASE_SW ; 2 = PVSA_CPU0
L4C3  IND-120NH-30-GP  pkg DISCRET-GB2  page 204 : 1 = VR_PVCCIN_CPU0_PHASE5 ; 2 = PVCCIN_CPU0
L4D1  IND-120NH-30-GP  pkg DISCRET-GB2  page 203 : 1 = VR_PVCCIN_CPU0_PHASE4 ; 2 = PVCCIN_CPU0
L4D2  IND-120NH-30-GP  pkg DISCRET-GB2  page 203 : 1 = VR_PVCCIN_CPU0_PHASE3 ; 2 = PVCCIN_CPU0
L4D3  IND-120NH-30-GP  pkg DISCRET-GB2  page 202 : 1 = VR_PVCCIN_CPU0_PHASE2 ; 2 = PVCCIN_CPU0
L4E1  IND-120NH-30-GP  pkg DISCRET-GB2  page 202 : 1 = VR_PVCCIN_CPU0_PHASE1 ; 2 = PVCCIN_CPU0
L4E2  IND-150NH-56-GP  pkg DISCRET-GA1  page 214 : 1 = VR_PVCCIO_CPU1_PH1_SW ; 2 = PVCCIO_CPU1
L4G1  INDUCTOR  0.47UH 1% IND  pkg SM  page 233 : 1 = VR_PVPP_GHJ_PHASE ; 2 = PVPP_GHJ
L7A1  IND-120NH-30-GP  pkg DISCRET-GB2  page 219 : 1 = VR_PVDDQ_DEF_PH1_SW ; 2 = PVDDQ_DEF
L7A2  IND-300NH-20-GP  pkg DISCRET-GB1  page 236 : 1 = VR_PVNN_PCH_PH1_PHASE_SW ; 2 = PVNN_PCH_STBY
L7A3  IND-120NH-30-GP  pkg DISCRET-GB2  page 219 : 1 = VR_PVDDQ_DEF_PH2_SW ; 2 = PVDDQ_DEF
L7A4  IND-300NH-20-GP  pkg DISCRET-GB1  page 236 : 1 = VR_P1V05_PCH_STBY_PH1_PHASE_SW ; 2 = P1V05_PCH_STBY
L7A5  IND-100NH-35-GP  pkg DISCRET-G8  page 220 : 1 = P12V_STBY ; 2 = VR_FET_SW_P12V_STBY_PVDDQ_DEF
L7B1  INDUCTOR  0.47UH 1% IND  pkg SM  page 232 : 1 = VR_PVPP_DEF_PHASE ; 2 = PVPP_DEF
L7C1  IND-100NH-35-GP  pkg DISCRET-G8  page 212 : 1 = P12V_STBY ; 2 = VR_FET_SW_P12V_STBY_PVCCIO_CPU0
L7C2  IND-150NH-56-GP  pkg DISCRET-GA1  page 212 : 1 = VR_PVCCIO_CPU0_PH1_SW ; 2 = PVCCIO_CPU0
